# S9S_MB_2U (Grand Teton) — schematic netlist excerpt (pin names and nets, part order shuffled) for the footprints in the layout excerpt that follows; sources: Cadence DE-HDL packaged netlist, KiCad conversion of 03242023_DA0F0TMBIJ0_F0T_Motherboard_J_brd_V01_OCP.brd

R2071  Q_RES  0 5% EMPTY  pkg 0402LF  page 213 : A = FM_BMC_SUSACK_R_N ; B = FM_SUSACK_N
H100  HOLE  EMPTY  pkg TH  page 311 : \1\ = GND

(kicad_pcb
	(version 20260206)
	(generator "pcbnew")
	(generator_version "10.0")
	(general
		(thickness 1.6)
		(legacy_teardrops no)
	)
	(paper "A4")
	(title_block
		(title "03242023_DA0F0TMBIJ0_F0T_Motherboard_J_brd_V01_OCP.brd")
		(comment 1 "Grand Teton / footprints 243-244 of 6105")
	)
	(layers
		(0 "F.Cu" signal "TOP")
		(4 "In1.Cu" signal "GND")
		(6 "In2.Cu" signal "IN1")
		(8 "In3.Cu" signal "GND1")
		(10 "In4.Cu" signal "IN2")
		(12 "In5.Cu" signal "GND2")
		(14 "In6.Cu" signal "IN3")
		(16 "In7.Cu" signal "GND3")
		(18 "In8.Cu" signal "VCC")
		(20 "In9.Cu" signal "VCC1")
		(22 "In10.Cu" signal "GND4")
		(24 "In11.Cu" signal "IN4")
		(26 "In12.Cu" signal "GND5")
		(28 "In13.Cu" signal "IN5")
		(30 "In14.Cu" signal "GND6")
		(32 "In15.Cu" signal "IN6")
		(34 "In16.Cu" signal "GND7")
		(2 "B.Cu" signal "BOTTOM")
		(9 "F.Adhes" user "F.Adhesive")
		(11 "B.Adhes" user "B.Adhesive")
		(13 "F.Paste" user "Package Geometry/Pastemask Top")
		(15 "B.Paste" user "Package Geometry/Pastemask Bottom")
		(5 "F.SilkS" user "Ref Des/Silkscreen Top")
		(7 "B.SilkS" user "Ref Des/Silkscreen Bottom")
		(1 "F.Mask" user "Board Geometry/Soldermask Top")
		(3 "B.Mask" user "Board Geometry/Soldermask Bottom")
		(17 "Dwgs.User" user "User.Drawings")
		(19 "Cmts.User" user "User.Comments")
		(21 "Eco1.User" user "User.Eco1")
		(23 "Eco2.User" user "User.Eco2")
		(25 "Edge.Cuts" user "Board Geometry/Outline")
		(27 "Margin" user)
		(31 "F.CrtYd" user "Package Geometry/Place Bound Top")
		(29 "B.CrtYd" user "Package Geometry/Place Bound Bottom")
		(35 "F.Fab" user "Ref Des/Assembly Top")
		(33 "B.Fab" user "Ref Des/Assembly Bottom")
	)
	(footprint ""
		(layer "F.Cu")
		(at 157.28188 -108.295948 180)
		(property "Reference" "R2071"
			(at 0 0 180)
			(layer "F.SilkS")
			(hide yes)
			(effects
				(font
					(size 1.27 1.27)
				)
			)
		)
		(property "Value" ""
			(at 0 0 180)
			(layer "F.Fab")
			(effects
				(font
					(size 1.27 1.27)
				)
			)
		)
		(duplicate_pad_numbers_are_jumpers no)
		(fp_line
			(start 0.7874 0.4064)
			(end -0.7874 0.4064)
			(stroke
				(width 0.1524)
				(type default)
			)
			(layer "F.SilkS")
		)
		(fp_line
			(start 0.7874 -0.4064)
			(end 0.7874 0.4064)
			(stroke
				(width 0.1524)
				(type default)
			)
			(layer "F.SilkS")
		)
		(fp_line
			(start -0.7874 0.4064)
			(end -0.7874 -0.4064)
			(stroke
				(width 0.1524)
				(type default)
			)
			(layer "F.SilkS")
		)
		(fp_line
			(start -0.7874 -0.4064)
			(end 0.7874 -0.4064)
			(stroke
				(width 0.1524)
				(type default)
			)
			(layer "F.SilkS")
		)
		(fp_line
			(start 0.67945 0.3048)
			(end 0.120396 0.3048)
			(stroke
				(width 0.1)
				(type default)
			)
			(layer "F.Fab")
		)
		(fp_line
			(start 0.67945 -0.3048)
			(end 0.67945 0.3048)
			(stroke
				(width 0.1)
				(type default)
			)
			(layer "F.Fab")
		)
		(fp_line
			(start 0.12065 -0.2794)
			(end 0.12065 -0.3048)
			(stroke
				(width 0.1)
				(type default)
			)
			(layer "F.Fab")
		)
		(fp_line
			(start 0.12065 -0.3048)
			(end 0.67945 -0.3048)
			(stroke
				(width 0.1)
				(type default)
			)
			(layer "F.Fab")
		)
		(fp_line
			(start 0.120396 0.3048)
			(end 0.120396 0.2794)
			(stroke
				(width 0.1)
				(type default)
			)
			(layer "F.Fab")
		)
		(fp_line
			(start 0.120396 0.2794)
			(end -0.12065 0.2794)
			(stroke
				(width 0.1)
				(type default)
			)
			(layer "F.Fab")
		)
		(fp_line
			(start -0.12065 0.3048)
			(end -0.67945 0.3048)
			(stroke
				(width 0.1)
				(type default)
			)
			(layer "F.Fab")
		)
		(fp_line
			(start -0.12065 0.2794)
			(end -0.12065 0.3048)
			(stroke
				(width 0.1)
				(type default)
			)
			(layer "F.Fab")
		)
		(fp_line
			(start -0.12065 -0.2794)
			(end 0.12065 -0.2794)
			(stroke
				(width 0.1)
				(type default)
			)
			(layer "F.Fab")
		)
		(fp_line
			(start -0.12065 -0.305054)
			(end -0.12065 -0.2794)
			(stroke
				(width 0.1)
				(type default)
			)
			(layer "F.Fab")
		)
		(fp_line
			(start -0.67945 0.3048)
			(end -0.67945 -0.305054)
			(stroke
				(width 0.1)
				(type default)
			)
			(layer "F.Fab")
		)
		(fp_line
			(start -0.67945 -0.305054)
			(end -0.12065 -0.305054)
			(stroke
				(width 0.1)
				(type default)
			)
			(layer "F.Fab")
		)
		(pad "1" smd circle
			(at -0.40005 0 180)
			(size 0 0)
			(layers "F.Cu" "F.Mask" "F.Paste")
			(net "FM_BMC_SUSACK_R_N")
		)
		(pad "2" smd circle
			(at 0.40005 0 180)
			(size 0 0)
			(layers "F.Cu" "F.Mask" "F.Paste")
			(net "FM_SUSACK_N")
		)
	)
	(footprint ""
		(layer "F.Cu")
		(at 6.999986 -22.29993)
		(property "Reference" "H100"
			(at -4.17322 -5.964428 0)
			(unlocked yes)
			(layer "F.SilkS")
			(effects
				(font
					(size 0.7874 0.5842)
					(thickness 0.1524)
				)
				(justify left)
			)
		)
		(property "Value" ""
			(at 0 0 0)
			(layer "F.Fab")
			(effects
				(font
					(size 1.27 1.27)
				)
			)
		)
		(duplicate_pad_numbers_are_jumpers no)
		(pad "1" thru_hole circle
			(at 0 0)
			(size 10.0076 10.0076)
			(drill 5.6134)
			(layers "*.Cu" "*.Mask")
			(remove_unused_layers no)
			(net "GND")
			(clearance -1.9431)
		)
	)
)
